(kicad_pcb
	(version 20241229)
	(generator "pcbnew")
	(generator_version "9.0")
	(general
		(thickness 1.599998)
		(legacy_teardrops no)
	)
	(paper "A4")
	(title_block
		(date "2023-02-12")
		(rev "1.1.5")
		(comment 9 "footprints 402-407 of 473")
	)
	(layers
		(0 "F.Cu" signal)
		(4 "In1.Cu" power "In1.GND")
		(6 "In2.Cu" signal)
		(8 "In3.Cu" power "In3.GND")
		(10 "In4.Cu" power "In4.VCC")
		(12 "In5.Cu" signal)
		(14 "In6.Cu" power "In6.VCC")
		(2 "B.Cu" signal)
		(9 "F.Adhes" user "F.Adhesive")
		(11 "B.Adhes" user "B.Adhesive")
		(13 "F.Paste" user)
		(15 "B.Paste" user)
		(5 "F.SilkS" user "F.Silkscreen")
		(7 "B.SilkS" user "B.Silkscreen")
		(1 "F.Mask" user)
		(3 "B.Mask" user)
		(17 "Dwgs.User" user "User.Drawings")
		(19 "Cmts.User" user "User.Comments")
		(21 "Eco1.User" user "User.Eco1")
		(23 "Eco2.User" user "User.Eco2")
		(25 "Edge.Cuts" user)
		(27 "Margin" user)
		(31 "F.CrtYd" user "F.Courtyard")
		(29 "B.CrtYd" user "B.Courtyard")
		(35 "F.Fab" user)
		(33 "B.Fab" user)
	)
	(footprint "antmicro-footprints:C_0603_1608Metric"
		(layer "B.Cu")
		(at 156.9 84.875 90)
		(descr "Capacitor SMD 0603")
		(tags "capacitor 0603")
		(property "Reference" "C143"
			(at 1.575 -0.6 270)
			(layer "B.SilkS")
			(effects
				(font
					(size 0.7 0.7)
					(thickness 0.15)
				)
				(justify left bottom mirror)
			)
		)
		(property "Value" "C_10n_0603"
			(at 0 -1.6 270)
			(layer "B.Fab")
			(effects
				(font
					(size 0.7 0.7)
					(thickness 0.15)
				)
				(justify left bottom mirror)
			)
		)
		(property "Description" " "
			(at 0 0 90)
			(layer "F.Fab")
			(hide yes)
			(effects
				(font
					(size 1.27 1.27)
					(thickness 0.15)
				)
			)
		)
		(property "Author" "Antmicro"
			(at 241.775 -72.025 0)
			(layer "B.Fab")
			(hide yes)
			(effects
				(font
					(size 1 1)
					(thickness 0.15)
				)
				(justify mirror)
			)
		)
		(property "Dielectric" ""
			(at 241.775 -72.025 0)
			(layer "B.Fab")
			(hide yes)
			(effects
				(font
					(size 1 1)
					(thickness 0.15)
				)
				(justify mirror)
			)
		)
		(property "License" "Apache-2.0"
			(at 241.775 -72.025 0)
			(layer "B.Fab")
			(hide yes)
			(effects
				(font
					(size 1 1)
					(thickness 0.15)
				)
				(justify mirror)
			)
		)
		(property "MPN" "06031C103JAT2A"
			(at 241.775 -72.025 0)
			(layer "B.Fab")
			(hide yes)
			(effects
				(font
					(size 1 1)
					(thickness 0.15)
				)
				(justify mirror)
			)
		)
		(property "Manufacturer" "AVX"
			(at 241.775 -72.025 0)
			(layer "B.Fab")
			(hide yes)
			(effects
				(font
					(size 1 1)
					(thickness 0.15)
				)
				(justify mirror)
			)
		)
		(property "Val" "10n"
			(at 241.775 -72.025 0)
			(layer "B.Fab")
			(hide yes)
			(effects
				(font
					(size 1 1)
					(thickness 0.15)
				)
				(justify mirror)
			)
		)
		(property "Voltage" ""
			(at 241.775 -72.025 0)
			(layer "B.Fab")
			(hide yes)
			(effects
				(font
					(size 1 1)
					(thickness 0.15)
				)
				(justify mirror)
			)
		)
		(sheetname "Supply")
		(sheetfile "supply.kicad_sch")
		(attr smd)
		(fp_line
			(start -0.3 -0.3)
			(end 0.3 -0.3)
			(stroke
				(width 0.15)
				(type solid)
			)
			(layer "B.SilkS")
		)
		(fp_line
			(start -0.3 0.3)
			(end 0.3 0.3)
			(stroke
				(width 0.15)
				(type solid)
			)
			(layer "B.SilkS")
		)
		(fp_rect
			(start -1.24 0.7)
			(end 1.24 -0.7)
			(stroke
				(width 0.05)
				(type solid)
			)
			(fill no)
			(layer "B.CrtYd")
		)
		(fp_rect
			(start -0.8 0.4)
			(end 0.8 -0.4)
			(stroke
				(width 0.15)
				(type solid)
			)
			(fill no)
			(layer "B.Fab")
		)
		(pad "1" smd roundrect
			(at -0.7 0 90)
			(size 0.6 0.8)
			(layers "B.Cu" "B.Mask" "B.Paste")
			(roundrect_rratio 0.2)
			(net 66 "VDDQ")
			(pintype "passive")
		)
		(pad "2" smd roundrect
			(at 0.7 0 90)
			(size 0.6 0.8)
			(layers "B.Cu" "B.Mask" "B.Paste")
			(roundrect_rratio 0.2)
			(net 5 "GND")
			(pintype "passive")
		)
	)
	(footprint "antmicro-footprints:C_0603_1608Metric"
		(layer "B.Cu")
		(at 177.85 66.5 90)
		(descr "Capacitor SMD 0603")
		(tags "capacitor 0603")
		(property "Reference" "C149"
			(at 1.4 1.35 270)
			(layer "B.SilkS")
			(effects
				(font
					(size 0.7 0.7)
					(thickness 0.15)
				)
				(justify left bottom mirror)
			)
		)
		(property "Value" "C_10n_0603"
			(at 0 -1.6 270)
			(layer "B.Fab")
			(effects
				(font
					(size 0.7 0.7)
					(thickness 0.15)
				)
				(justify left bottom mirror)
			)
		)
		(property "Description" " "
			(at 0 0 90)
			(layer "F.Fab")
			(hide yes)
			(effects
				(font
					(size 1.27 1.27)
					(thickness 0.15)
				)
			)
		)
		(property "Author" "Antmicro"
			(at 244.35 -111.35 0)
			(layer "B.Fab")
			(hide yes)
			(effects
				(font
					(size 1 1)
					(thickness 0.15)
				)
				(justify mirror)
			)
		)
		(property "Dielectric" ""
			(at 244.35 -111.35 0)
			(layer "B.Fab")
			(hide yes)
			(effects
				(font
					(size 1 1)
					(thickness 0.15)
				)
				(justify mirror)
			)
		)
		(property "License" "Apache-2.0"
			(at 244.35 -111.35 0)
			(layer "B.Fab")
			(hide yes)
			(effects
				(font
					(size 1 1)
					(thickness 0.15)
				)
				(justify mirror)
			)
		)
		(property "MPN" "06031C103JAT2A"
			(at 244.35 -111.35 0)
			(layer "B.Fab")
			(hide yes)
			(effects
				(font
					(size 1 1)
					(thickness 0.15)
				)
				(justify mirror)
			)
		)
		(property "Manufacturer" "AVX"
			(at 244.35 -111.35 0)
			(layer "B.Fab")
			(hide yes)
			(effects
				(font
					(size 1 1)
					(thickness 0.15)
				)
				(justify mirror)
			)
		)
		(property "Val" "10n"
			(at 244.35 -111.35 0)
			(layer "B.Fab")
			(hide yes)
			(effects
				(font
					(size 1 1)
					(thickness 0.15)
				)
				(justify mirror)
			)
		)
		(property "Voltage" ""
			(at 244.35 -111.35 0)
			(layer "B.Fab")
			(hide yes)
			(effects
				(font
					(size 1 1)
					(thickness 0.15)
				)
				(justify mirror)
			)
		)
		(sheetname "Supply")
		(sheetfile "supply.kicad_sch")
		(attr smd)
		(fp_line
			(start -0.3 -0.3)
			(end 0.3 -0.3)
			(stroke
				(width 0.15)
				(type solid)
			)
			(layer "B.SilkS")
		)
		(fp_line
			(start -0.3 0.3)
			(end 0.3 0.3)
			(stroke
				(width 0.15)
				(type solid)
			)
			(layer "B.SilkS")
		)
		(fp_rect
			(start -1.24 0.7)
			(end 1.24 -0.7)
			(stroke
				(width 0.05)
				(type solid)
			)
			(fill no)
			(layer "B.CrtYd")
		)
		(fp_rect
			(start -0.8 0.4)
			(end 0.8 -0.4)
			(stroke
				(width 0.15)
				(type solid)
			)
			(fill no)
			(layer "B.Fab")
		)
		(pad "1" smd roundrect
			(at -0.7 0 90)
			(size 0.6 0.8)
			(layers "B.Cu" "B.Mask" "B.Paste")
			(roundrect_rratio 0.2)
			(net 641 "1V8_DDR")
			(pintype "passive")
		)
		(pad "2" smd roundrect
			(at 0.7 0 90)
			(size 0.6 0.8)
			(layers "B.Cu" "B.Mask" "B.Paste")
			(roundrect_rratio 0.2)
			(net 5 "GND")
			(pintype "passive")
		)
	)
	(footprint "antmicro-footprints:C_0603_1608Metric"
		(layer "B.Cu")
		(at 182.136328 97.897157)
		(descr "Capacitor SMD 0603")
		(tags "capacitor 0603")
		(property "Reference" "C151"
			(at 1.363672 1.402843 180)
			(layer "B.SilkS")
			(effects
				(font
					(size 0.7 0.7)
					(thickness 0.15)
				)
				(justify left bottom mirror)
			)
		)
		(property "Value" "C_10n_0603"
			(at 0 -1.6 180)
			(layer "B.Fab")
			(effects
				(font
					(size 0.7 0.7)
					(thickness 0.15)
				)
				(justify left bottom mirror)
			)
		)
		(property "Description" " "
			(at 0 0 0)
			(layer "F.Fab")
			(hide yes)
			(effects
				(font
					(size 1.27 1.27)
					(thickness 0.15)
				)
			)
		)
		(property "Author" "Antmicro"
			(at 0 0 0)
			(layer "B.Fab")
			(hide yes)
			(effects
				(font
					(size 1 1)
					(thickness 0.15)
				)
				(justify mirror)
			)
		)
		(property "Dielectric" ""
			(at 0 0 0)
			(layer "B.Fab")
			(hide yes)
			(effects
				(font
					(size 1 1)
					(thickness 0.15)
				)
				(justify mirror)
			)
		)
		(property "License" "Apache-2.0"
			(at 0 0 0)
			(layer "B.Fab")
			(hide yes)
			(effects
				(font
					(size 1 1)
					(thickness 0.15)
				)
				(justify mirror)
			)
		)
		(property "MPN" "06031C103JAT2A"
			(at 0 0 0)
			(layer "B.Fab")
			(hide yes)
			(effects
				(font
					(size 1 1)
					(thickness 0.15)
				)
				(justify mirror)
			)
		)
		(property "Manufacturer" "AVX"
			(at 0 0 0)
			(layer "B.Fab")
			(hide yes)
			(effects
				(font
					(size 1 1)
					(thickness 0.15)
				)
				(justify mirror)
			)
		)
		(property "Val" "10n"
			(at 0 0 0)
			(layer "B.Fab")
			(hide yes)
			(effects
				(font
					(size 1 1)
					(thickness 0.15)
				)
				(justify mirror)
			)
		)
		(property "Voltage" ""
			(at 0 0 0)
			(layer "B.Fab")
			(hide yes)
			(effects
				(font
					(size 1 1)
					(thickness 0.15)
				)
				(justify mirror)
			)
		)
		(sheetname "Supply")
		(sheetfile "supply.kicad_sch")
		(attr smd)
		(fp_line
			(start -0.3 -0.3)
			(end 0.3 -0.3)
			(stroke
				(width 0.15)
				(type solid)
			)
			(layer "B.SilkS")
		)
		(fp_line
			(start -0.3 0.3)
			(end 0.3 0.3)
			(stroke
				(width 0.15)
				(type solid)
			)
			(layer "B.SilkS")
		)
		(fp_rect
			(start -1.24 0.7)
			(end 1.24 -0.7)
			(stroke
				(width 0.05)
				(type solid)
			)
			(fill no)
			(layer "B.CrtYd")
		)
		(fp_rect
			(start -0.8 0.4)
			(end 0.8 -0.4)
			(stroke
				(width 0.15)
				(type solid)
			)
			(fill no)
			(layer "B.Fab")
		)
		(pad "1" smd roundrect
			(at -0.7 0)
			(size 0.6 0.8)
			(layers "B.Cu" "B.Mask" "B.Paste")
			(roundrect_rratio 0.2)
			(net 460 "1V8_SYS")
			(pintype "passive")
		)
		(pad "2" smd roundrect
			(at 0.7 0)
			(size 0.6 0.8)
			(layers "B.Cu" "B.Mask" "B.Paste")
			(roundrect_rratio 0.2)
			(net 5 "GND")
			(pintype "passive")
		)
	)
	(footprint "antmicro-footprints:C_0603_1608Metric"
		(layer "B.Cu")
		(at 182.236328 86.597157)
		(descr "Capacitor SMD 0603")
		(tags "capacitor 0603")
		(property "Reference" "C147"
			(at 1.4 1.4 180)
			(layer "B.SilkS")
			(effects
				(font
					(size 0.7 0.7)
					(thickness 0.15)
				)
				(justify left bottom mirror)
			)
		)
		(property "Value" "C_10n_0603"
			(at 0 -1.6 180)
			(layer "B.Fab")
			(effects
				(font
					(size 0.7 0.7)
					(thickness 0.15)
				)
				(justify left bottom mirror)
			)
		)
		(property "Description" " "
			(at 0 0 0)
			(layer "F.Fab")
			(hide yes)
			(effects
				(font
					(size 1.27 1.27)
					(thickness 0.15)
				)
			)
		)
		(property "Author" "Antmicro"
			(at 0 0 0)
			(layer "B.Fab")
			(hide yes)
			(effects
				(font
					(size 1 1)
					(thickness 0.15)
				)
				(justify mirror)
			)
		)
		(property "Dielectric" ""
			(at 0 0 0)
			(layer "B.Fab")
			(hide yes)
			(effects
				(font
					(size 1 1)
					(thickness 0.15)
				)
				(justify mirror)
			)
		)
		(property "License" "Apache-2.0"
			(at 0 0 0)
			(layer "B.Fab")
			(hide yes)
			(effects
				(font
					(size 1 1)
					(thickness 0.15)
				)
				(justify mirror)
			)
		)
		(property "MPN" "06031C103JAT2A"
			(at 0 0 0)
			(layer "B.Fab")
			(hide yes)
			(effects
				(font
					(size 1 1)
					(thickness 0.15)
				)
				(justify mirror)
			)
		)
		(property "Manufacturer" "AVX"
			(at 0 0 0)
			(layer "B.Fab")
			(hide yes)
			(effects
				(font
					(size 1 1)
					(thickness 0.15)
				)
				(justify mirror)
			)
		)
		(property "Val" "10n"
			(at 0 0 0)
			(layer "B.Fab")
			(hide yes)
			(effects
				(font
					(size 1 1)
					(thickness 0.15)
				)
				(justify mirror)
			)
		)
		(property "Voltage" ""
			(at 0 0 0)
			(layer "B.Fab")
			(hide yes)
			(effects
				(font
					(size 1 1)
					(thickness 0.15)
				)
				(justify mirror)
			)
		)
		(sheetname "Supply")
		(sheetfile "supply.kicad_sch")
		(attr smd)
		(fp_line
			(start -0.3 -0.3)
			(end 0.3 -0.3)
			(stroke
				(width 0.15)
				(type solid)
			)
			(layer "B.SilkS")
		)
		(fp_line
			(start -0.3 0.3)
			(end 0.3 0.3)
			(stroke
				(width 0.15)
				(type solid)
			)
			(layer "B.SilkS")
		)
		(fp_rect
			(start -1.24 0.7)
			(end 1.24 -0.7)
			(stroke
				(width 0.05)
				(type solid)
			)
			(fill no)
			(layer "B.CrtYd")
		)
		(fp_rect
			(start -0.8 0.4)
			(end 0.8 -0.4)
			(stroke
				(width 0.15)
				(type solid)
			)
			(fill no)
			(layer "B.Fab")
		)
		(pad "1" smd roundrect
			(at -0.7 0)
			(size 0.6 0.8)
			(layers "B.Cu" "B.Mask" "B.Paste")
			(roundrect_rratio 0.2)
			(net 460 "1V8_SYS")
			(pintype "passive")
		)
		(pad "2" smd roundrect
			(at 0.7 0)
			(size 0.6 0.8)
			(layers "B.Cu" "B.Mask" "B.Paste")
			(roundrect_rratio 0.2)
			(net 5 "GND")
			(pintype "passive")
		)
	)
	(footprint "antmicro-footprints:C_0402_1005Metric"
		(layer "B.Cu")
		(at 173.5 105.125 180)
		(descr "Capacitor SMD 0402")
		(tags "capacitor SMD 0402")
		(property "Reference" "C89"
			(at -1.2 -1.275 0)
			(layer "B.SilkS")
			(effects
				(font
					(size 0.7 0.7)
					(thickness 0.15)
				)
				(justify left bottom mirror)
			)
		)
		(property "Value" "C_4u7_0402"
			(at 0 -1.4 0)
			(layer "B.Fab")
			(effects
				(font
					(size 0.7 0.7)
					(thickness 0.15)
				)
				(justify left bottom mirror)
			)
		)
		(property "Description" " "
			(at 0 0 180)
			(layer "F.Fab")
			(hide yes)
			(effects
				(font
					(size 1.27 1.27)
					(thickness 0.15)
				)
			)
		)
		(property "Author" "Antmicro"
			(at 347 210.25 0)
			(layer "B.Fab")
			(hide yes)
			(effects
				(font
					(size 1 1)
					(thickness 0.15)
				)
				(justify mirror)
			)
		)
		(property "Dielectric" ""
			(at 347 210.25 0)
			(layer "B.Fab")
			(hide yes)
			(effects
				(font
					(size 1 1)
					(thickness 0.15)
				)
				(justify mirror)
			)
		)
		(property "License" "Apache-2.0"
			(at 347 210.25 0)
			(layer "B.Fab")
			(hide yes)
			(effects
				(font
					(size 1 1)
					(thickness 0.15)
				)
				(justify mirror)
			)
		)
		(property "MPN" "GRM155R61A475MEAAD"
			(at 347 210.25 0)
			(layer "B.Fab")
			(hide yes)
			(effects
				(font
					(size 1 1)
					(thickness 0.15)
				)
				(justify mirror)
			)
		)
		(property "Manufacturer" "Murata"
			(at 347 210.25 0)
			(layer "B.Fab")
			(hide yes)
			(effects
				(font
					(size 1 1)
					(thickness 0.15)
				)
				(justify mirror)
			)
		)
		(property "Val" "4u7"
			(at 347 210.25 0)
			(layer "B.Fab")
			(hide yes)
			(effects
				(font
					(size 1 1)
					(thickness 0.15)
				)
				(justify mirror)
			)
		)
		(property "Voltage" ""
			(at 347 210.25 0)
			(layer "B.Fab")
			(hide yes)
			(effects
				(font
					(size 1 1)
					(thickness 0.15)
				)
				(justify mirror)
			)
		)
		(sheetname "FPGA power")
		(sheetfile "fpga-power.kicad_sch")
		(attr smd)
		(fp_rect
			(start -0.94 0.47)
			(end 0.94 -0.47)
			(stroke
				(width 0.05)
				(type solid)
			)
			(fill no)
			(layer "B.CrtYd")
		)
		(fp_rect
			(start -0.499 0.249)
			(end 0.499 -0.249)
			(stroke
				(width 0.15)
				(type solid)
			)
			(fill no)
			(layer "B.Fab")
		)
		(pad "1" smd roundrect
			(at -0.484 0 180)
			(size 0.59 0.64)
			(layers "B.Cu" "B.Mask" "B.Paste")
			(roundrect_rratio 0.25)
			(net 459 "3V3_SYS")
			(pintype "passive")
		)
		(pad "2" smd roundrect
			(at 0.484 0 180)
			(size 0.59 0.64)
			(layers "B.Cu" "B.Mask" "B.Paste")
			(roundrect_rratio 0.25)
			(net 5 "GND")
			(pintype "passive")
		)
	)
	(footprint "antmicro-footprints:R_0603_1608Metric"
		(layer "B.Cu")
		(at 156.936328 87.797157 90)
		(descr "Resistor SMD 0603")
		(tags "resistor SMD 0603")
		(property "Reference" "R6"
			(at 0.697157 -0.636328 270)
			(layer "B.SilkS")
			(effects
				(font
					(size 0.7 0.7)
					(thickness 0.15)
				)
				(justify left bottom mirror)
			)
		)
		(property "Value" "R_1k_0603"
			(at 0 -1.6 270)
			(layer "B.Fab")
			(effects
				(font
					(size 0.7 0.7)
					(thickness 0.15)
				)
				(justify left bottom mirror)
			)
		)
		(property "Description" "1k resistor in 0603 package with 1% tolerance"
			(at 0 0 90)
			(layer "F.Fab")
			(hide yes)
			(effects
				(font
					(size 1.27 1.27)
					(thickness 0.15)
				)
			)
		)
		(property "Author" "Antmicro"
			(at 244.733485 -69.139171 0)
			(layer "B.Fab")
			(hide yes)
			(effects
				(font
					(size 1 1)
					(thickness 0.15)
				)
				(justify mirror)
			)
		)
		(property "License" "Apache-2.0"
			(at 244.733485 -69.139171 0)
			(layer "B.Fab")
			(hide yes)
			(effects
				(font
					(size 1 1)
					(thickness 0.15)
				)
				(justify mirror)
			)
		)
		(property "MPN" "CR0603-FX-1001ELF"
			(at 244.733485 -69.139171 0)
			(layer "B.Fab")
			(hide yes)
			(effects
				(font
					(size 1 1)
					(thickness 0.15)
				)
				(justify mirror)
			)
		)
		(property "Manufacturer" "Bourns"
			(at 244.733485 -69.139171 0)
			(layer "B.Fab")
			(hide yes)
			(effects
				(font
					(size 1 1)
					(thickness 0.15)
				)
				(justify mirror)
			)
		)
		(property "Tolerance" "1%"
			(at 244.733485 -69.139171 0)
			(layer "B.Fab")
			(hide yes)
			(effects
				(font
					(size 1 1)
					(thickness 0.15)
				)
				(justify mirror)
			)
		)
		(property "Val" "1k"
			(at 244.733485 -69.139171 0)
			(layer "B.Fab")
			(hide yes)
			(effects
				(font
					(size 1 1)
					(thickness 0.15)
				)
				(justify mirror)
			)
		)
		(sheetname "FPGA Banks")
		(sheetfile "fpga-banks.kicad_sch")
		(attr smd)
		(fp_line
			(start -0.3 -0.3)
			(end 0.3 -0.3)
			(stroke
				(width 0.15)
				(type solid)
			)
			(layer "B.SilkS")
		)
		(fp_line
			(start -0.3 0.3)
			(end 0.3 0.3)
			(stroke
				(width 0.15)
				(type solid)
			)
			(layer "B.SilkS")
		)
		(fp_rect
			(start -1.25 0.7)
			(end 1.25 -0.7)
			(stroke
				(width 0.05)
				(type solid)
			)
			(fill no)
			(layer "B.CrtYd")
		)
		(fp_rect
			(start -0.8 0.4)
			(end 0.8 -0.4)
			(stroke
				(width 0.15)
				(type solid)
			)
			(fill no)
			(layer "B.Fab")
		)
		(pad "1" smd roundrect
			(at -0.7 0 90)
			(size 0.6 0.8)
			(layers "B.Cu" "B.Mask" "B.Paste")
			(roundrect_rratio 0.2)
			(net 510 "VREF_34")
			(pintype "passive")
		)
		(pad "2" smd roundrect
			(at 0.7 0 90)
			(size 0.6 0.8)
			(layers "B.Cu" "B.Mask" "B.Paste")
			(roundrect_rratio 0.2)
			(net 5 "GND")
			(pintype "passive")
		)
	)
)
